# T6G (Grand Teton) — schematic netlist excerpt (pin names and nets, part order shuffled) for the footprints in the layout excerpt that follows; sources: Cadence DE-HDL packaged netlist, KiCad conversion of 04192023_DAF0TMB3IC0_F0TG_MB_C_brd_V02_OCP.brd

U160  74LV4052PW  IC  pkg TSSOP16_0-65_5X4-4XH  page 171
  \2y0\  = TP_JTAG_SCM_SLOT3_R_TMS
  \2y2\  = JTAG_SCM_PLD_R_TMS
  \2z\  = JTAG_SCM_TMS
  \2y3\  = JTAG_SCM_PLD_R_TMS
  \2y1\  = JTAG_SCM_MUX_R_TMS
  E_N  = U160_EN_N
  VEE  = GND
  GND  = GND
  S1  = SCM_JTAG_MUX_S1
  S0  = SCM_JTAG_MUX_S0_R1
  \1y3\  = JTAG_SCM_PLD_R_TCK
  \1y0\  = TP_JTAG_SCM_SLOT3_R_TCK
  \1z\  = JTAG_SCM_TCK
  \1y1\  = JTAG_SCM_MUX_R_TCK
  \1y2\  = JTAG_SCM_PLD_R_TCK
  VCC  = P3V3_AUX

R1253  Q_RES  33 5% CHIP  pkg 0402LF  page 164 : A = UART_LS_EN_N ; B = UART_LS_EN_R_N

(kicad_pcb
	(version 20260206)
	(generator "pcbnew")
	(generator_version "10.0")
	(general
		(thickness 1.6)
		(legacy_teardrops no)
	)
	(paper "A4")
	(title_block
		(title "04192023_DAF0TMB3IC0_F0TG_MB_C_brd_V02_OCP.brd")
		(comment 1 "Grand Teton / footprints 3069-3070 of 8354")
	)
	(layers
		(0 "F.Cu" signal "TOP")
		(4 "In1.Cu" signal "GND")
		(6 "In2.Cu" signal "IN1")
		(8 "In3.Cu" signal "GND1")
		(10 "In4.Cu" signal "IN2")
		(12 "In5.Cu" signal "GND2")
		(14 "In6.Cu" signal "IN3")
		(16 "In7.Cu" signal "GND3")
		(18 "In8.Cu" signal "VCC")
		(20 "In9.Cu" signal "VCC1")
		(22 "In10.Cu" signal "GND4")
		(24 "In11.Cu" signal "IN4")
		(26 "In12.Cu" signal "GND5")
		(28 "In13.Cu" signal "IN5")
		(30 "In14.Cu" signal "GND6")
		(32 "In15.Cu" signal "IN6")
		(34 "In16.Cu" signal "GND7")
		(2 "B.Cu" signal "BOTTOM")
		(9 "F.Adhes" user "F.Adhesive")
		(11 "B.Adhes" user "B.Adhesive")
		(13 "F.Paste" user "Package Geometry/Pastemask Top")
		(15 "B.Paste" user "Package Geometry/Pastemask Bottom")
		(5 "F.SilkS" user "Ref Des/Silkscreen Top")
		(7 "B.SilkS" user "Ref Des/Silkscreen Bottom")
		(1 "F.Mask" user "Board Geometry/Soldermask Top")
		(3 "B.Mask" user "Board Geometry/Soldermask Bottom")
		(17 "Dwgs.User" user "User.Drawings")
		(19 "Cmts.User" user "User.Comments")
		(21 "Eco1.User" user "User.Eco1")
		(23 "Eco2.User" user "User.Eco2")
		(25 "Edge.Cuts" user "Board Geometry/Outline")
		(27 "Margin" user)
		(31 "F.CrtYd" user "Package Geometry/Place Bound Top")
		(29 "B.CrtYd" user "Package Geometry/Place Bound Bottom")
		(35 "F.Fab" user "Ref Des/Assembly Top")
		(33 "B.Fab" user "Ref Des/Assembly Bottom")
	)
	(footprint ""
		(layer "F.Cu")
		(at 111.86541 -58.827162)
		(property "Reference" "U160"
			(at -2.482088 -3.213862 0)
			(unlocked yes)
			(layer "F.SilkS")
			(effects
				(font
					(size 0.7874 0.5842)
					(thickness 0.1524)
				)
				(justify left)
			)
		)
		(property "Value" ""
			(at 0 0 0)
			(layer "F.Fab")
			(effects
				(font
					(size 1.27 1.27)
				)
			)
		)
		(duplicate_pad_numbers_are_jumpers no)
		(fp_line
			(start -2.112264 -2.549906)
			(end -0.704088 -2.549906)
			(stroke
				(width 0.1524)
				(type default)
			)
			(layer "F.SilkS")
		)
		(fp_line
			(start -2.112264 2.549906)
			(end -2.112264 -2.549906)
			(stroke
				(width 0.1524)
				(type default)
			)
			(layer "F.SilkS")
		)
		(fp_line
			(start -0.704088 -2.549906)
			(end 0 -1.845818)
			(stroke
				(width 0.1524)
				(type default)
			)
			(layer "F.SilkS")
		)
		(fp_line
			(start 0 -1.845818)
			(end 0.704088 -2.549906)
			(stroke
				(width 0.1524)
				(type default)
			)
			(layer "F.SilkS")
		)
		(fp_line
			(start 0.704088 -2.549906)
			(end 2.112264 -2.549906)
			(stroke
				(width 0.1524)
				(type default)
			)
			(layer "F.SilkS")
		)
		(fp_line
			(start 2.112264 -2.549906)
			(end 2.112264 2.549906)
			(stroke
				(width 0.1524)
				(type default)
			)
			(layer "F.SilkS")
		)
		(fp_line
			(start 2.112264 2.549906)
			(end -2.112264 2.549906)
			(stroke
				(width 0.1524)
				(type default)
			)
			(layer "F.SilkS")
		)
		(fp_poly
			(pts
				(xy -4.917186 -2.8829) (xy -4.917186 -1.8669) (xy -3.901186 -2.3749)
			)
			(stroke
				(width 0)
				(type default)
			)
			(fill yes)
			(layer "F.SilkS")
		)
		(fp_line
			(start -2.249932 -2.549906)
			(end 2.249932 -2.549906)
			(stroke
				(width 0.1)
				(type default)
			)
			(layer "F.Fab")
		)
		(fp_line
			(start -2.249932 2.549906)
			(end -2.249932 -2.549906)
			(stroke
				(width 0.1)
				(type default)
			)
			(layer "F.Fab")
		)
		(fp_line
			(start 2.249932 -2.549906)
			(end 2.249932 2.549906)
			(stroke
				(width 0.1)
				(type default)
			)
			(layer "F.Fab")
		)
		(fp_line
			(start 2.249932 2.549906)
			(end -2.249932 2.549906)
			(stroke
				(width 0.1)
				(type default)
			)
			(layer "F.Fab")
		)
		(fp_poly
			(pts
				(xy -4.917186 -2.8829) (xy -4.917186 -1.8669) (xy -3.901186 -2.3749)
			)
			(stroke
				(width 0)
				(type default)
			)
			(fill yes)
			(layer "F.Fab")
		)
		(pad "1" smd rect
			(at -2.925064 -2.3749 270)
			(size 0.6096 1.3716)
			(layers "F.Cu" "F.Mask" "F.Paste")
			(net "TP_JTAG_SCM_SLOT3_R_TMS")
		)
		(pad "2" smd rect
			(at -2.925064 -1.625092 270)
			(size 0.4064 1.3716)
			(layers "F.Cu" "F.Mask" "F.Paste")
			(net "JTAG_SCM_PLD_R_TMS")
		)
		(pad "3" smd rect
			(at -2.925064 -0.975106 270)
			(size 0.4064 1.3716)
			(layers "F.Cu" "F.Mask" "F.Paste")
			(net "JTAG_SCM_TMS")
		)
		(pad "4" smd rect
			(at -2.925064 -0.32512 270)
			(size 0.4064 1.3716)
			(layers "F.Cu" "F.Mask" "F.Paste")
			(net "JTAG_SCM_PLD_R_TMS")
		)
		(pad "5" smd rect
			(at -2.925064 0.32512 270)
			(size 0.4064 1.3716)
			(layers "F.Cu" "F.Mask" "F.Paste")
			(net "JTAG_SCM_MUX_R_TMS")
		)
		(pad "6" smd rect
			(at -2.925064 0.975106 270)
			(size 0.4064 1.3716)
			(layers "F.Cu" "F.Mask" "F.Paste")
			(net "U160_EN_N")
		)
		(pad "7" smd rect
			(at -2.925064 1.625092 270)
			(size 0.4064 1.3716)
			(layers "F.Cu" "F.Mask" "F.Paste")
			(net "GND")
		)
		(pad "8" smd rect
			(at -2.925064 2.3749 270)
			(size 0.6096 1.3716)
			(layers "F.Cu" "F.Mask" "F.Paste")
			(net "GND")
		)
		(pad "9" smd rect
			(at 2.925064 2.3749 270)
			(size 0.6096 1.3716)
			(layers "F.Cu" "F.Mask" "F.Paste")
			(net "SCM_JTAG_MUX_S1")
		)
		(pad "10" smd rect
			(at 2.925064 1.625092 270)
			(size 0.4064 1.3716)
			(layers "F.Cu" "F.Mask" "F.Paste")
			(net "SCM_JTAG_MUX_S0_R1")
		)
		(pad "11" smd rect
			(at 2.925064 0.975106 270)
			(size 0.4064 1.3716)
			(layers "F.Cu" "F.Mask" "F.Paste")
			(net "JTAG_SCM_PLD_R_TCK")
		)
		(pad "12" smd rect
			(at 2.925064 0.32512 270)
			(size 0.4064 1.3716)
			(layers "F.Cu" "F.Mask" "F.Paste")
			(net "TP_JTAG_SCM_SLOT3_R_TCK")
		)
		(pad "13" smd rect
			(at 2.925064 -0.32512 270)
			(size 0.4064 1.3716)
			(layers "F.Cu" "F.Mask" "F.Paste")
			(net "JTAG_SCM_TCK")
		)
		(pad "14" smd rect
			(at 2.925064 -0.975106 270)
			(size 0.4064 1.3716)
			(layers "F.Cu" "F.Mask" "F.Paste")
			(net "JTAG_SCM_MUX_R_TCK")
		)
		(pad "15" smd rect
			(at 2.925064 -1.625092 270)
			(size 0.4064 1.3716)
			(layers "F.Cu" "F.Mask" "F.Paste")
			(net "JTAG_SCM_PLD_R_TCK")
		)
		(pad "16" smd rect
			(at 2.925064 -2.3749 270)
			(size 0.6096 1.3716)
			(layers "F.Cu" "F.Mask" "F.Paste")
			(net "P3V3_AUX")
		)
	)
	(footprint ""
		(layer "F.Cu")
		(at 364.155228 -29.886656 180)
		(property "Reference" "R1253"
			(at 0 0 180)
			(layer "F.SilkS")
			(hide yes)
			(effects
				(font
					(size 1.27 1.27)
				)
			)
		)
		(property "Value" ""
			(at 0 0 180)
			(layer "F.Fab")
			(effects
				(font
					(size 1.27 1.27)
				)
			)
		)
		(duplicate_pad_numbers_are_jumpers no)
		(fp_line
			(start 0.7874 0.4064)
			(end -0.7874 0.4064)
			(stroke
				(width 0.1524)
				(type default)
			)
			(layer "F.SilkS")
		)
		(fp_line
			(start 0.7874 -0.4064)
			(end 0.7874 0.4064)
			(stroke
				(width 0.1524)
				(type default)
			)
			(layer "F.SilkS")
		)
		(fp_line
			(start -0.7874 0.4064)
			(end -0.7874 -0.4064)
			(stroke
				(width 0.1524)
				(type default)
			)
			(layer "F.SilkS")
		)
		(fp_line
			(start -0.7874 -0.4064)
			(end 0.7874 -0.4064)
			(stroke
				(width 0.1524)
				(type default)
			)
			(layer "F.SilkS")
		)
		(fp_line
			(start 0.67945 0.3048)
			(end 0.120396 0.3048)
			(stroke
				(width 0.1)
				(type default)
			)
			(layer "F.Fab")
		)
		(fp_line
			(start 0.67945 -0.3048)
			(end 0.67945 0.3048)
			(stroke
				(width 0.1)
				(type default)
			)
			(layer "F.Fab")
		)
		(fp_line
			(start 0.12065 -0.2794)
			(end 0.12065 -0.3048)
			(stroke
				(width 0.1)
				(type default)
			)
			(layer "F.Fab")
		)
		(fp_line
			(start 0.12065 -0.3048)
			(end 0.67945 -0.3048)
			(stroke
				(width 0.1)
				(type default)
			)
			(layer "F.Fab")
		)
		(fp_line
			(start 0.120396 0.3048)
			(end 0.120396 0.2794)
			(stroke
				(width 0.1)
				(type default)
			)
			(layer "F.Fab")
		)
		(fp_line
			(start 0.120396 0.2794)
			(end -0.12065 0.2794)
			(stroke
				(width 0.1)
				(type default)
			)
			(layer "F.Fab")
		)
		(fp_line
			(start -0.12065 0.3048)
			(end -0.67945 0.3048)
			(stroke
				(width 0.1)
				(type default)
			)
			(layer "F.Fab")
		)
		(fp_line
			(start -0.12065 0.2794)
			(end -0.12065 0.3048)
			(stroke
				(width 0.1)
				(type default)
			)
			(layer "F.Fab")
		)
		(fp_line
			(start -0.12065 -0.2794)
			(end 0.12065 -0.2794)
			(stroke
				(width 0.1)
				(type default)
			)
			(layer "F.Fab")
		)
		(fp_line
			(start -0.12065 -0.305054)
			(end -0.12065 -0.2794)
			(stroke
				(width 0.1)
				(type default)
			)
			(layer "F.Fab")
		)
		(fp_line
			(start -0.67945 0.3048)
			(end -0.67945 -0.305054)
			(stroke
				(width 0.1)
				(type default)
			)
			(layer "F.Fab")
		)
		(fp_line
			(start -0.67945 -0.305054)
			(end -0.12065 -0.305054)
			(stroke
				(width 0.1)
				(type default)
			)
			(layer "F.Fab")
		)
		(pad "1" smd circle
			(at -0.40005 0 180)
			(size 0 0)
			(layers "F.Cu" "F.Mask" "F.Paste")
			(net "UART_LS_EN_N")
		)
		(pad "2" smd circle
			(at 0.40005 0 180)
			(size 0 0)
			(layers "F.Cu" "F.Mask" "F.Paste")
			(net "UART_LS_EN_R_N")
		)
	)
)
